(kicad_pcb
	(version 20260206)
	(generator "pcbnew")
	(generator_version "10.0")
	(general
		(thickness 1.6)
		(legacy_teardrops no)
	)
	(paper "A4")
	(title_block
		(title "Bryce Canyon_F.DPB_16315-1-OCP.brd")
		(comment 1 "Bryce Canyon / footprints 1753-1758 of 2223")
	)
	(layers
		(0 "F.Cu" signal "TOP")
		(4 "In1.Cu" signal "L2GND")
		(6 "In2.Cu" signal "L3")
		(8 "In3.Cu" signal "L4GND")
		(10 "In4.Cu" signal "L5")
		(12 "In5.Cu" signal "L6VCC")
		(14 "In6.Cu" signal "L7VCC")
		(16 "In7.Cu" signal "L8")
		(18 "In8.Cu" signal "L9GND")
		(20 "In9.Cu" signal "L10")
		(22 "In10.Cu" signal "L11GND")
		(2 "B.Cu" signal "BOTTOM")
		(9 "F.Adhes" user "F.Adhesive")
		(11 "B.Adhes" user "B.Adhesive")
		(13 "F.Paste" user "Package Geometry/Pastemask Top")
		(15 "B.Paste" user "Package Geometry/Pastemask Bottom")
		(5 "F.SilkS" user "Ref Des/Silkscreen Top")
		(7 "B.SilkS" user "Ref Des/Silkscreen Bottom")
		(1 "F.Mask" user "Board Geometry/Soldermask Top")
		(3 "B.Mask" user "Board Geometry/Soldermask Bottom")
		(17 "Dwgs.User" user "User.Drawings")
		(19 "Cmts.User" user "User.Comments")
		(21 "Eco1.User" user "User.Eco1")
		(23 "Eco2.User" user "User.Eco2")
		(25 "Edge.Cuts" user "Board Geometry/Outline")
		(27 "Margin" user)
		(31 "F.CrtYd" user "Package Geometry/Place Bound Top")
		(29 "B.CrtYd" user "Package Geometry/Place Bound Bottom")
		(35 "F.Fab" user "Ref Des/Assembly Top")
		(33 "B.Fab" user "Ref Des/Assembly Bottom")
	)
	(footprint ""
		(layer "F.Cu")
		(at 172.593 -174.857918)
		(property "Reference" "Q104"
			(at 0 0 0)
			(layer "F.SilkS")
			(hide yes)
			(effects
				(font
					(size 1.27 1.27)
				)
			)
		)
		(property "Value" "AO4407AL-GP"
			(at -3.707384 -1.5367 0)
			(unlocked yes)
			(layer "F.Fab")
			(hide yes)
			(effects
				(font
					(size 1.016 1.016)
					(thickness 0.1524)
				)
			)
		)
		(property "Device Type" "SOIC8H69"
			(at -3.707384 -3.0607 0)
			(unlocked yes)
			(layer "F.Fab")
			(hide yes)
			(effects
				(font
					(size 1.016 1.016)
					(thickness 0.1524)
				)
			)
		)
		(duplicate_pad_numbers_are_jumpers no)
		(fp_line
			(start -2.7432 -1.4224)
			(end -2.7432 1.4224)
			(stroke
				(width 0.1524)
				(type default)
			)
			(layer "F.SilkS")
		)
		(fp_line
			(start -2.7432 1.4224)
			(end -2.6416 1.4224)
			(stroke
				(width 0.1524)
				(type default)
			)
			(layer "F.SilkS")
		)
		(fp_line
			(start -2.7432 1.4224)
			(end 2.1336 1.4224)
			(stroke
				(width 0.1524)
				(type default)
			)
			(layer "F.SilkS")
		)
		(fp_line
			(start -2.7178 -0.508)
			(end -2.1844 -0.0508)
			(stroke
				(width 0.1524)
				(type default)
			)
			(layer "F.SilkS")
		)
		(fp_line
			(start -2.6289 3.4417)
			(end -2.6289 1.4732)
			(stroke
				(width 0.381)
				(type default)
			)
			(layer "F.SilkS")
		)
		(fp_line
			(start -2.1844 -0.0508)
			(end -2.7178 0.508)
			(stroke
				(width 0.1524)
				(type default)
			)
			(layer "F.SilkS")
		)
		(fp_line
			(start 2.1336 -1.4224)
			(end -2.7432 -1.4224)
			(stroke
				(width 0.1524)
				(type default)
			)
			(layer "F.SilkS")
		)
		(fp_line
			(start 2.1336 1.4224)
			(end 2.1336 -1.4224)
			(stroke
				(width 0.1524)
				(type default)
			)
			(layer "F.SilkS")
		)
		(fp_poly
			(pts
				(xy -2.2098 -1.4224) (xy -2.2098 1.4224) (xy 2.2098 1.4224) (xy 2.2098 -1.4224)
			)
			(stroke
				(width 0)
				(type default)
			)
			(fill yes)
			(layer "F.SilkS")
		)
		(fp_rect
			(start -2.450084 2.999994)
			(end 2.450084 -2.999994)
			(stroke
				(width 0)
				(type default)
			)
			(fill no)
			(layer "F.CrtYd")
		)
		(fp_poly
			(pts
				(xy -2.8194 3.6322) (xy -2.8194 -3.6322) (xy 2.8194 -3.6322) (xy 2.8194 1.18364) (xy 2.450084 1.18364)
				(xy 2.450084 -2.999994) (xy -2.450084 -2.999994) (xy -2.450084 2.999994) (xy 2.450084 2.999994)
				(xy 2.450084 1.18618) (xy 2.8194 1.18618) (xy 2.8194 3.6322)
			)
			(stroke
				(width 0)
				(type default)
			)
			(fill no)
			(layer "F.CrtYd")
		)
		(fp_rect
			(start -2.8194 3.6322)
			(end 2.8194 -3.6322)
			(stroke
				(width 0)
				(type default)
			)
			(fill no)
			(layer "F.Fab")
		)
		(pad "1" smd rect
			(at -1.905 2.54)
			(size 0.635 1.651)
			(layers "F.Cu" "F.Mask" "F.Paste")
			(net "P12V_A")
		)
		(pad "2" smd rect
			(at -0.635 2.54)
			(size 0.635 1.651)
			(layers "F.Cu" "F.Mask" "F.Paste")
			(net "P12V_A")
		)
		(pad "3" smd rect
			(at 0.635 2.54)
			(size 0.635 1.651)
			(layers "F.Cu" "F.Mask" "F.Paste")
			(net "P12V_A")
		)
		(pad "4" smd rect
			(at 1.905 2.54)
			(size 0.635 1.651)
			(layers "F.Cu" "F.Mask" "F.Paste")
			(net "SW_HDD_N17")
		)
		(pad "5" smd rect
			(at 1.905 -2.54)
			(size 0.635 1.651)
			(layers "F.Cu" "F.Mask" "F.Paste")
			(net "P12V_HDD17")
		)
		(pad "6" smd rect
			(at 0.635 -2.54)
			(size 0.635 1.651)
			(layers "F.Cu" "F.Mask" "F.Paste")
			(net "P12V_HDD17")
		)
		(pad "7" smd rect
			(at -0.635 -2.54)
			(size 0.635 1.651)
			(layers "F.Cu" "F.Mask" "F.Paste")
			(net "P12V_HDD17")
		)
		(pad "8" smd rect
			(at -1.905 -2.54)
			(size 0.635 1.651)
			(layers "F.Cu" "F.Mask" "F.Paste")
			(net "P12V_HDD17")
		)
	)
	(footprint ""
		(layer "F.Cu")
		(at 240.03 -395.9098 180)
		(property "Reference" "C590"
			(at 0 0 180)
			(layer "F.SilkS")
			(hide yes)
			(effects
				(font
					(size 1.27 1.27)
				)
			)
		)
		(property "Value" "SCD1U25V2KX-2-GP"
			(at 1.1811 -2.7051 180)
			(unlocked yes)
			(layer "F.Fab")
			(hide yes)
			(effects
				(font
					(size 1.016 1.016)
					(thickness 0.1524)
				)
			)
		)
		(property "Device Type" "C402H22"
			(at 1.1811 -4.2291 180)
			(unlocked yes)
			(layer "F.Fab")
			(hide yes)
			(effects
				(font
					(size 1.016 1.016)
					(thickness 0.1524)
				)
			)
		)
		(duplicate_pad_numbers_are_jumpers no)
		(fp_rect
			(start -0.4318 0.9525)
			(end 0.4318 -0.9525)
			(stroke
				(width 0)
				(type default)
			)
			(fill no)
			(layer "F.CrtYd")
		)
		(fp_rect
			(start -0.4318 0.9525)
			(end 0.4318 -0.9525)
			(stroke
				(width 0)
				(type default)
			)
			(fill no)
			(layer "F.Fab")
		)
		(pad "1" smd custom
			(at 0 -0.4445 180)
			(size 0.1524 0.1524)
			(layers "F.Cu" "F.Mask" "F.Paste")
			(net "MB3_ISET_R")
			(options
				(clearance outline)
				(anchor circle)
			)
			(primitives
				(gr_poly
					(pts
						(arc
							(start 0.3048 -0.2032)
							(mid 0.275042 -0.275042)
							(end 0.2032 -0.3048)
						)
						(arc
							(start -0.2032 -0.3048)
							(mid -0.275042 -0.275042)
							(end -0.3048 -0.2032)
						)
						(arc
							(start -0.3048 0.2032)
							(mid -0.275042 0.275042)
							(end -0.2032 0.3048)
						)
						(arc
							(start 0.2032 0.3048)
							(mid 0.275042 0.275042)
							(end 0.3048 0.2032)
						)
					)
					(width 0)
					(fill yes)
				)
			)
		)
		(pad "2" smd custom
			(at 0 0.4445 180)
			(size 0.1524 0.1524)
			(layers "F.Cu" "F.Mask" "F.Paste")
			(net "AGND_CURRENT_DPB")
			(options
				(clearance outline)
				(anchor circle)
			)
			(primitives
				(gr_poly
					(pts
						(arc
							(start 0.3048 -0.2032)
							(mid 0.275042 -0.275042)
							(end 0.2032 -0.3048)
						)
						(arc
							(start -0.2032 -0.3048)
							(mid -0.275042 -0.275042)
							(end -0.3048 -0.2032)
						)
						(arc
							(start -0.3048 0.2032)
							(mid -0.275042 0.275042)
							(end -0.2032 0.3048)
						)
						(arc
							(start 0.2032 0.3048)
							(mid 0.275042 0.275042)
							(end 0.3048 0.2032)
						)
					)
					(width 0)
					(fill yes)
				)
			)
		)
	)
	(footprint ""
		(layer "F.Cu")
		(at 55.790846 -304.462942 180)
		(property "Reference" "C60"
			(at 0 0 180)
			(layer "F.SilkS")
			(hide yes)
			(effects
				(font
					(size 1.27 1.27)
				)
			)
		)
		(property "Value" "SC1U25V3KX-GP"
			(at 0 -2.8194 180)
			(unlocked yes)
			(layer "F.Fab")
			(hide yes)
			(effects
				(font
					(size 1.016 1.016)
					(thickness 0.1524)
				)
			)
		)
		(property "Device Type" "C603H36"
			(at 0 -4.3434 180)
			(unlocked yes)
			(layer "F.Fab")
			(hide yes)
			(effects
				(font
					(size 1.016 1.016)
					(thickness 0.1524)
				)
			)
		)
		(duplicate_pad_numbers_are_jumpers no)
		(fp_line
			(start 0.508 0)
			(end -0.508 0)
			(stroke
				(width 0.2032)
				(type default)
			)
			(layer "F.SilkS")
		)
		(fp_rect
			(start -0.5842 1.3335)
			(end 0.5842 -1.3335)
			(stroke
				(width 0)
				(type default)
			)
			(fill no)
			(layer "F.CrtYd")
		)
		(fp_rect
			(start -0.5842 1.3335)
			(end 0.5842 -1.3335)
			(stroke
				(width 0)
				(type default)
			)
			(fill no)
			(layer "F.Fab")
		)
		(pad "1" smd custom
			(at 0 -0.762 180)
			(size 0.2159 0.2159)
			(layers "F.Cu" "F.Mask" "F.Paste")
			(net "P12V_HDD1")
			(options
				(clearance outline)
				(anchor circle)
			)
			(primitives
				(gr_poly
					(pts
						(arc
							(start -0.3302 -0.4318)
							(mid -0.402042 -0.402042)
							(end -0.4318 -0.3302)
						)
						(arc
							(start -0.4318 0.3302)
							(mid -0.402042 0.402042)
							(end -0.3302 0.4318)
						)
						(arc
							(start 0.3302 0.4318)
							(mid 0.402042 0.402042)
							(end 0.4318 0.3302)
						)
						(arc
							(start 0.4318 -0.3302)
							(mid 0.402042 -0.402042)
							(end 0.3302 -0.4318)
						)
					)
					(width 0)
					(fill yes)
				)
			)
		)
		(pad "2" smd custom
			(at 0 0.762 180)
			(size 0.2159 0.2159)
			(layers "F.Cu" "F.Mask" "F.Paste")
			(net "GND")
			(options
				(clearance outline)
				(anchor circle)
			)
			(primitives
				(gr_poly
					(pts
						(arc
							(start -0.3302 -0.4318)
							(mid -0.402042 -0.402042)
							(end -0.4318 -0.3302)
						)
						(arc
							(start -0.4318 0.3302)
							(mid -0.402042 0.402042)
							(end -0.3302 0.4318)
						)
						(arc
							(start 0.3302 0.4318)
							(mid 0.402042 0.402042)
							(end 0.4318 0.3302)
						)
						(arc
							(start 0.4318 -0.3302)
							(mid 0.402042 -0.402042)
							(end 0.3302 -0.4318)
						)
					)
					(width 0)
					(fill yes)
				)
			)
		)
	)
	(footprint ""
		(layer "F.Cu")
		(at 138.018266 -135.339074 -90)
		(property "Reference" "R1043"
			(at 0 0 270)
			(layer "F.SilkS")
			(hide yes)
			(effects
				(font
					(size 1.27 1.27)
				)
			)
		)
		(property "Value" "0R2J-2-GP"
			(at 0.064008 -3.993896 270)
			(unlocked yes)
			(layer "F.Fab")
			(hide yes)
			(effects
				(font
					(size 1.016 1.016)
					(thickness 0.1524)
				)
			)
		)
		(property "Device Type" "R402H16"
			(at 0.064008 -5.517896 270)
			(unlocked yes)
			(layer "F.Fab")
			(hide yes)
			(effects
				(font
					(size 1.016 1.016)
					(thickness 0.1524)
				)
			)
		)
		(duplicate_pad_numbers_are_jumpers no)
		(fp_line
			(start -0.508 -0.9398)
			(end -0.508 0.9398)
			(stroke
				(width 0.1524)
				(type default)
			)
			(layer "F.SilkS")
		)
		(fp_line
			(start 0.508 -0.9398)
			(end -0.508 -0.9398)
			(stroke
				(width 0.1524)
				(type default)
			)
			(layer "F.SilkS")
		)
		(fp_rect
			(start -0.508 0.9398)
			(end 0.508 -0.9398)
			(stroke
				(width 0)
				(type default)
			)
			(fill no)
			(layer "F.CrtYd")
		)
		(fp_rect
			(start -0.508 0.9398)
			(end 0.508 -0.9398)
			(stroke
				(width 0)
				(type default)
			)
			(fill no)
			(layer "F.Fab")
		)
		(pad "1" smd custom
			(at 0 -0.4445 270)
			(size 0.1397 0.1397)
			(layers "F.Cu" "F.Mask" "F.Paste")
			(net "MB0_SDA_R")
			(options
				(clearance outline)
				(anchor circle)
			)
			(primitives
				(gr_poly
					(pts
						(arc
							(start -0.1778 -0.2794)
							(mid -0.249642 -0.249642)
							(end -0.2794 -0.1778)
						)
						(arc
							(start -0.2794 0.1778)
							(mid -0.249642 0.249642)
							(end -0.1778 0.2794)
						)
						(arc
							(start 0.1778 0.2794)
							(mid 0.249642 0.249642)
							(end 0.2794 0.1778)
						)
						(arc
							(start 0.2794 -0.1778)
							(mid 0.249642 -0.249642)
							(end 0.1778 -0.2794)
						)
					)
					(width 0)
					(fill yes)
				)
			)
		)
		(pad "2" smd custom
			(at 0 0.4445 270)
			(size 0.1397 0.1397)
			(layers "F.Cu" "F.Mask" "F.Paste")
			(net "I2C_BMC_A_MISC_SDA")
			(options
				(clearance outline)
				(anchor circle)
			)
			(primitives
				(gr_poly
					(pts
						(arc
							(start -0.1778 -0.2794)
							(mid -0.249642 -0.249642)
							(end -0.2794 -0.1778)
						)
						(arc
							(start -0.2794 0.1778)
							(mid -0.249642 0.249642)
							(end -0.1778 0.2794)
						)
						(arc
							(start 0.1778 0.2794)
							(mid 0.249642 0.249642)
							(end 0.2794 0.1778)
						)
						(arc
							(start 0.2794 -0.1778)
							(mid 0.249642 -0.249642)
							(end 0.1778 -0.2794)
						)
					)
					(width 0)
					(fill yes)
				)
			)
		)
	)
	(footprint ""
		(layer "F.Cu")
		(at 332.74 -48.554894 -90)
		(property "Reference" "R827"
			(at 0 0 270)
			(layer "F.SilkS")
			(hide yes)
			(effects
				(font
					(size 1.27 1.27)
				)
			)
		)
		(property "Value" "4K7R2J-2-GP"
			(at 0.064008 -3.993896 270)
			(unlocked yes)
			(layer "F.Fab")
			(hide yes)
			(effects
				(font
					(size 1.016 1.016)
					(thickness 0.1524)
				)
			)
		)
		(property "Device Type" "R402H16"
			(at 0.064008 -5.517896 270)
			(unlocked yes)
			(layer "F.Fab")
			(hide yes)
			(effects
				(font
					(size 1.016 1.016)
					(thickness 0.1524)
				)
			)
		)
		(duplicate_pad_numbers_are_jumpers no)
		(fp_line
			(start -0.508 -0.9398)
			(end -0.508 0.9398)
			(stroke
				(width 0.1524)
				(type default)
			)
			(layer "F.SilkS")
		)
		(fp_line
			(start 0.508 -0.9398)
			(end -0.508 -0.9398)
			(stroke
				(width 0.1524)
				(type default)
			)
			(layer "F.SilkS")
		)
		(fp_rect
			(start -0.508 0.9398)
			(end 0.508 -0.9398)
			(stroke
				(width 0)
				(type default)
			)
			(fill no)
			(layer "F.CrtYd")
		)
		(fp_rect
			(start -0.508 0.9398)
			(end 0.508 -0.9398)
			(stroke
				(width 0)
				(type default)
			)
			(fill no)
			(layer "F.Fab")
		)
		(pad "1" smd custom
			(at 0 -0.4445 270)
			(size 0.1397 0.1397)
			(layers "F.Cu" "F.Mask" "F.Paste")
			(net "P12V_A")
			(options
				(clearance outline)
				(anchor circle)
			)
			(primitives
				(gr_poly
					(pts
						(arc
							(start -0.1778 -0.2794)
							(mid -0.249642 -0.249642)
							(end -0.2794 -0.1778)
						)
						(arc
							(start -0.2794 0.1778)
							(mid -0.249642 0.249642)
							(end -0.1778 0.2794)
						)
						(arc
							(start 0.1778 0.2794)
							(mid 0.249642 0.249642)
							(end 0.2794 0.1778)
						)
						(arc
							(start 0.2794 -0.1778)
							(mid 0.249642 -0.249642)
							(end 0.1778 -0.2794)
						)
					)
					(width 0)
					(fill yes)
				)
			)
		)
		(pad "2" smd custom
			(at 0 0.4445 270)
			(size 0.1397 0.1397)
			(layers "F.Cu" "F.Mask" "F.Paste")
			(net "SW_HDD_P30")
			(options
				(clearance outline)
				(anchor circle)
			)
			(primitives
				(gr_poly
					(pts
						(arc
							(start -0.1778 -0.2794)
							(mid -0.249642 -0.249642)
							(end -0.2794 -0.1778)
						)
						(arc
							(start -0.2794 0.1778)
							(mid -0.249642 0.249642)
							(end -0.1778 0.2794)
						)
						(arc
							(start 0.1778 0.2794)
							(mid 0.249642 0.249642)
							(end 0.2794 0.1778)
						)
						(arc
							(start 0.2794 -0.1778)
							(mid 0.249642 -0.249642)
							(end 0.1778 -0.2794)
						)
					)
					(width 0)
					(fill yes)
				)
			)
		)
	)
	(footprint ""
		(layer "F.Cu")
		(at 362.310426 -134.558278 180)
		(property "Reference" "C567"
			(at 0 0 180)
			(layer "F.SilkS")
			(hide yes)
			(effects
				(font
					(size 1.27 1.27)
				)
			)
		)
		(property "Value" "SC1U16V3KX-5GP"
			(at 0 -2.8194 180)
			(unlocked yes)
			(layer "F.Fab")
			(hide yes)
			(effects
				(font
					(size 1.016 1.016)
					(thickness 0.1524)
				)
			)
		)
		(property "Device Type" "C603H36"
			(at 0 -4.3434 180)
			(unlocked yes)
			(layer "F.Fab")
			(hide yes)
			(effects
				(font
					(size 1.016 1.016)
					(thickness 0.1524)
				)
			)
		)
		(duplicate_pad_numbers_are_jumpers no)
		(fp_line
			(start 0.508 0)
			(end -0.508 0)
			(stroke
				(width 0.2032)
				(type default)
			)
			(layer "F.SilkS")
		)
		(fp_rect
			(start -0.5842 1.3335)
			(end 0.5842 -1.3335)
			(stroke
				(width 0)
				(type default)
			)
			(fill no)
			(layer "F.CrtYd")
		)
		(fp_rect
			(start -0.5842 1.3335)
			(end 0.5842 -1.3335)
			(stroke
				(width 0)
				(type default)
			)
			(fill no)
			(layer "F.Fab")
		)
		(pad "1" smd custom
			(at 0 -0.762 180)
			(size 0.2159 0.2159)
			(layers "F.Cu" "F.Mask" "F.Paste")
			(net "MB1_CM_UV_R")
			(options
				(clearance outline)
				(anchor circle)
			)
			(primitives
				(gr_poly
					(pts
						(arc
							(start -0.3302 -0.4318)
							(mid -0.402042 -0.402042)
							(end -0.4318 -0.3302)
						)
						(arc
							(start -0.4318 0.3302)
							(mid -0.402042 0.402042)
							(end -0.3302 0.4318)
						)
						(arc
							(start 0.3302 0.4318)
							(mid 0.402042 0.402042)
							(end 0.4318 0.3302)
						)
						(arc
							(start 0.4318 -0.3302)
							(mid 0.402042 -0.402042)
							(end 0.3302 -0.4318)
						)
					)
					(width 0)
					(fill yes)
				)
			)
		)
		(pad "2" smd custom
			(at 0 0.762 180)
			(size 0.2159 0.2159)
			(layers "F.Cu" "F.Mask" "F.Paste")
			(net "AGND_CURRENT_MONOB")
			(options
				(clearance outline)
				(anchor circle)
			)
			(primitives
				(gr_poly
					(pts
						(arc
							(start -0.3302 -0.4318)
							(mid -0.402042 -0.402042)
							(end -0.4318 -0.3302)
						)
						(arc
							(start -0.4318 0.3302)
							(mid -0.402042 0.402042)
							(end -0.3302 0.4318)
						)
						(arc
							(start 0.3302 0.4318)
							(mid 0.402042 0.402042)
							(end 0.4318 0.3302)
						)
						(arc
							(start 0.4318 -0.3302)
							(mid 0.402042 -0.402042)
							(end 0.3302 -0.4318)
						)
					)
					(width 0)
					(fill yes)
				)
			)
		)
	)
)
